# S9S_MB_2U (Grand Teton) — schematic netlist excerpt (pin names and nets, part order shuffled) for the footprints in the layout excerpt that follows; sources: Cadence DE-HDL packaged netlist, KiCad conversion of 03242023_DA0F0TMBIJ0_F0T_Motherboard_J_brd_V01_OCP.brd

R3530  Q_RES  4.7K 5% CHIP  pkg 0402LF  page 194 : A = P3V3_E1S_0 ; B = SMB_E1S_3V3AUX_ISO_SCL_R
R372  Q_RES  10K 1% CHIP  pkg 0402LF  page 198 : A = FM_PCH_BOOT_BIOS_STRAP ; B = GND

(kicad_pcb
	(version 20260206)
	(generator "pcbnew")
	(generator_version "10.0")
	(general
		(thickness 1.6)
		(legacy_teardrops no)
	)
	(paper "A4")
	(title_block
		(title "03242023_DA0F0TMBIJ0_F0T_Motherboard_J_brd_V01_OCP.brd")
		(comment 1 "Grand Teton / footprints 1418-1419 of 6105")
	)
	(layers
		(0 "F.Cu" signal "TOP")
		(4 "In1.Cu" signal "GND")
		(6 "In2.Cu" signal "IN1")
		(8 "In3.Cu" signal "GND1")
		(10 "In4.Cu" signal "IN2")
		(12 "In5.Cu" signal "GND2")
		(14 "In6.Cu" signal "IN3")
		(16 "In7.Cu" signal "GND3")
		(18 "In8.Cu" signal "VCC")
		(20 "In9.Cu" signal "VCC1")
		(22 "In10.Cu" signal "GND4")
		(24 "In11.Cu" signal "IN4")
		(26 "In12.Cu" signal "GND5")
		(28 "In13.Cu" signal "IN5")
		(30 "In14.Cu" signal "GND6")
		(32 "In15.Cu" signal "IN6")
		(34 "In16.Cu" signal "GND7")
		(2 "B.Cu" signal "BOTTOM")
		(9 "F.Adhes" user "F.Adhesive")
		(11 "B.Adhes" user "B.Adhesive")
		(13 "F.Paste" user "Package Geometry/Pastemask Top")
		(15 "B.Paste" user "Package Geometry/Pastemask Bottom")
		(5 "F.SilkS" user "Ref Des/Silkscreen Top")
		(7 "B.SilkS" user "Ref Des/Silkscreen Bottom")
		(1 "F.Mask" user "Board Geometry/Soldermask Top")
		(3 "B.Mask" user "Board Geometry/Soldermask Bottom")
		(17 "Dwgs.User" user "User.Drawings")
		(19 "Cmts.User" user "User.Comments")
		(21 "Eco1.User" user "User.Eco1")
		(23 "Eco2.User" user "User.Eco2")
		(25 "Edge.Cuts" user "Board Geometry/Outline")
		(27 "Margin" user)
		(31 "F.CrtYd" user "Package Geometry/Place Bound Top")
		(29 "B.CrtYd" user "Package Geometry/Place Bound Bottom")
		(35 "F.Fab" user "Ref Des/Assembly Top")
		(33 "B.Fab" user "Ref Des/Assembly Bottom")
	)
	(footprint ""
		(layer "F.Cu")
		(at 315.110622 -53.203348 180)
		(property "Reference" "R372"
			(at 0 0 180)
			(layer "F.SilkS")
			(hide yes)
			(effects
				(font
					(size 1.27 1.27)
				)
			)
		)
		(property "Value" ""
			(at 0 0 180)
			(layer "F.Fab")
			(effects
				(font
					(size 1.27 1.27)
				)
			)
		)
		(duplicate_pad_numbers_are_jumpers no)
		(fp_line
			(start 0.7874 0.4064)
			(end -0.7874 0.4064)
			(stroke
				(width 0.1524)
				(type default)
			)
			(layer "F.SilkS")
		)
		(fp_line
			(start 0.7874 -0.4064)
			(end 0.7874 0.4064)
			(stroke
				(width 0.1524)
				(type default)
			)
			(layer "F.SilkS")
		)
		(fp_line
			(start -0.7874 0.4064)
			(end -0.7874 -0.4064)
			(stroke
				(width 0.1524)
				(type default)
			)
			(layer "F.SilkS")
		)
		(fp_line
			(start -0.7874 -0.4064)
			(end 0.7874 -0.4064)
			(stroke
				(width 0.1524)
				(type default)
			)
			(layer "F.SilkS")
		)
		(fp_line
			(start 0.67945 0.3048)
			(end 0.120396 0.3048)
			(stroke
				(width 0.1)
				(type default)
			)
			(layer "F.Fab")
		)
		(fp_line
			(start 0.67945 -0.3048)
			(end 0.67945 0.3048)
			(stroke
				(width 0.1)
				(type default)
			)
			(layer "F.Fab")
		)
		(fp_line
			(start 0.12065 -0.2794)
			(end 0.12065 -0.3048)
			(stroke
				(width 0.1)
				(type default)
			)
			(layer "F.Fab")
		)
		(fp_line
			(start 0.12065 -0.3048)
			(end 0.67945 -0.3048)
			(stroke
				(width 0.1)
				(type default)
			)
			(layer "F.Fab")
		)
		(fp_line
			(start 0.120396 0.3048)
			(end 0.120396 0.2794)
			(stroke
				(width 0.1)
				(type default)
			)
			(layer "F.Fab")
		)
		(fp_line
			(start 0.120396 0.2794)
			(end -0.12065 0.2794)
			(stroke
				(width 0.1)
				(type default)
			)
			(layer "F.Fab")
		)
		(fp_line
			(start -0.12065 0.3048)
			(end -0.67945 0.3048)
			(stroke
				(width 0.1)
				(type default)
			)
			(layer "F.Fab")
		)
		(fp_line
			(start -0.12065 0.2794)
			(end -0.12065 0.3048)
			(stroke
				(width 0.1)
				(type default)
			)
			(layer "F.Fab")
		)
		(fp_line
			(start -0.12065 -0.2794)
			(end 0.12065 -0.2794)
			(stroke
				(width 0.1)
				(type default)
			)
			(layer "F.Fab")
		)
		(fp_line
			(start -0.12065 -0.305054)
			(end -0.12065 -0.2794)
			(stroke
				(width 0.1)
				(type default)
			)
			(layer "F.Fab")
		)
		(fp_line
			(start -0.67945 0.3048)
			(end -0.67945 -0.305054)
			(stroke
				(width 0.1)
				(type default)
			)
			(layer "F.Fab")
		)
		(fp_line
			(start -0.67945 -0.305054)
			(end -0.12065 -0.305054)
			(stroke
				(width 0.1)
				(type default)
			)
			(layer "F.Fab")
		)
		(pad "1" smd circle
			(at -0.40005 0 180)
			(size 0 0)
			(layers "F.Cu" "F.Mask" "F.Paste")
			(net "FM_PCH_BOOT_BIOS_STRAP")
		)
		(pad "2" smd circle
			(at 0.40005 0 180)
			(size 0 0)
			(layers "F.Cu" "F.Mask" "F.Paste")
			(net "GND")
		)
	)
	(footprint ""
		(layer "F.Cu")
		(at 221.67088 -43.525948 180)
		(property "Reference" "R3530"
			(at 0 0 180)
			(layer "F.SilkS")
			(hide yes)
			(effects
				(font
					(size 1.27 1.27)
				)
			)
		)
		(property "Value" ""
			(at 0 0 180)
			(layer "F.Fab")
			(effects
				(font
					(size 1.27 1.27)
				)
			)
		)
		(duplicate_pad_numbers_are_jumpers no)
		(fp_line
			(start 0.7874 0.4064)
			(end -0.7874 0.4064)
			(stroke
				(width 0.1524)
				(type default)
			)
			(layer "F.SilkS")
		)
		(fp_line
			(start 0.7874 -0.4064)
			(end 0.7874 0.4064)
			(stroke
				(width 0.1524)
				(type default)
			)
			(layer "F.SilkS")
		)
		(fp_line
			(start -0.7874 0.4064)
			(end -0.7874 -0.4064)
			(stroke
				(width 0.1524)
				(type default)
			)
			(layer "F.SilkS")
		)
		(fp_line
			(start -0.7874 -0.4064)
			(end 0.7874 -0.4064)
			(stroke
				(width 0.1524)
				(type default)
			)
			(layer "F.SilkS")
		)
		(fp_line
			(start 0.67945 0.3048)
			(end 0.120396 0.3048)
			(stroke
				(width 0.1)
				(type default)
			)
			(layer "F.Fab")
		)
		(fp_line
			(start 0.67945 -0.3048)
			(end 0.67945 0.3048)
			(stroke
				(width 0.1)
				(type default)
			)
			(layer "F.Fab")
		)
		(fp_line
			(start 0.12065 -0.2794)
			(end 0.12065 -0.3048)
			(stroke
				(width 0.1)
				(type default)
			)
			(layer "F.Fab")
		)
		(fp_line
			(start 0.12065 -0.3048)
			(end 0.67945 -0.3048)
			(stroke
				(width 0.1)
				(type default)
			)
			(layer "F.Fab")
		)
		(fp_line
			(start 0.120396 0.3048)
			(end 0.120396 0.2794)
			(stroke
				(width 0.1)
				(type default)
			)
			(layer "F.Fab")
		)
		(fp_line
			(start 0.120396 0.2794)
			(end -0.12065 0.2794)
			(stroke
				(width 0.1)
				(type default)
			)
			(layer "F.Fab")
		)
		(fp_line
			(start -0.12065 0.3048)
			(end -0.67945 0.3048)
			(stroke
				(width 0.1)
				(type default)
			)
			(layer "F.Fab")
		)
		(fp_line
			(start -0.12065 0.2794)
			(end -0.12065 0.3048)
			(stroke
				(width 0.1)
				(type default)
			)
			(layer "F.Fab")
		)
		(fp_line
			(start -0.12065 -0.2794)
			(end 0.12065 -0.2794)
			(stroke
				(width 0.1)
				(type default)
			)
			(layer "F.Fab")
		)
		(fp_line
			(start -0.12065 -0.305054)
			(end -0.12065 -0.2794)
			(stroke
				(width 0.1)
				(type default)
			)
			(layer "F.Fab")
		)
		(fp_line
			(start -0.67945 0.3048)
			(end -0.67945 -0.305054)
			(stroke
				(width 0.1)
				(type default)
			)
			(layer "F.Fab")
		)
		(fp_line
			(start -0.67945 -0.305054)
			(end -0.12065 -0.305054)
			(stroke
				(width 0.1)
				(type default)
			)
			(layer "F.Fab")
		)
		(pad "1" smd circle
			(at -0.40005 0 180)
			(size 0 0)
			(layers "F.Cu" "F.Mask" "F.Paste")
			(net "P3V3_E1S_0")
		)
		(pad "2" smd circle
			(at 0.40005 0 180)
			(size 0 0)
			(layers "F.Cu" "F.Mask" "F.Paste")
			(net "SMB_E1S_3V3AUX_ISO_SCL_R")
		)
	)
)
